(kicad_pcb
	(version 20241229)
	(generator "pcbnew")
	(generator_version "9.0")
	(general
		(thickness 1.62)
		(legacy_teardrops no)
	)
	(paper "A4")
	(title_block
		(title "OCuLink to 10GbE adapter")
		(date "2026-02-23")
		(rev "1.1.0")
		(company "Antmicro Ltd")
		(comment 1 "www.antmicro.com")
		(comment 9 "footprints 119-124 of 510")
	)
	(layers
		(0 "F.Cu" signal)
		(4 "In1.Cu" signal)
		(6 "In2.Cu" signal)
		(8 "In3.Cu" signal)
		(10 "In4.Cu" signal)
		(12 "In5.Cu" signal)
		(14 "In6.Cu" signal)
		(2 "B.Cu" signal)
		(9 "F.Adhes" user "F.Adhesive")
		(11 "B.Adhes" user "B.Adhesive")
		(13 "F.Paste" user)
		(15 "B.Paste" user)
		(5 "F.SilkS" user "F.Silkscreen")
		(7 "B.SilkS" user "B.Silkscreen")
		(1 "F.Mask" user)
		(3 "B.Mask" user)
		(17 "Dwgs.User" user "User.Drawings")
		(19 "Cmts.User" user "User.Comments")
		(21 "Eco1.User" user "User.Eco1")
		(23 "Eco2.User" user "User.Eco2")
		(25 "Edge.Cuts" user)
		(27 "Margin" user)
		(31 "F.CrtYd" user "F.Courtyard")
		(29 "B.CrtYd" user "B.Courtyard")
		(35 "F.Fab" user)
		(33 "B.Fab" user)
	)
	(footprint "antmicro-footprints:LED_0603_1608Metric_G"
		(layer "F.Cu")
		(at 52.3 78 -90)
		(descr "LED SMD 0603 Green")
		(tags "LED SMD 0603 Green")
		(property "Reference" "D11"
			(at -3.3 -0.25 90)
			(layer "F.SilkS")
			(effects
				(font
					(size 0.7 0.7)
					(thickness 0.15)
				)
				(justify right top)
			)
		)
		(property "Value" "LED_G_0603_LG_L29K-G2J1-24-Z"
			(at -0.001 1.599 90)
			(layer "F.Fab")
			(hide yes)
			(effects
				(font
					(size 0.7 0.7)
					(thickness 0.15)
				)
				(justify right top)
			)
		)
		(property "Datasheet" "https://look.ams-osram.com/m/19ee86b3ae0ee95b/original/LG-L29K.pdf"
			(at 0 0 90)
			(layer "F.Fab")
			(hide yes)
			(effects
				(font
					(size 1.27 1.27)
					(thickness 0.15)
				)
			)
		)
		(property "Description" "LED, Green, SMD, 0603, 20 mA, 1.7 V, 570 nm"
			(at 0 0 90)
			(layer "F.Fab")
			(hide yes)
			(effects
				(font
					(size 1.27 1.27)
					(thickness 0.15)
				)
			)
		)
		(property "MPN" "LG L29K-G2J1-24-Z"
			(at 0 0 270)
			(unlocked yes)
			(layer "F.Fab")
			(hide yes)
			(effects
				(font
					(size 1 1)
					(thickness 0.15)
				)
			)
		)
		(property "Manufacturer" "OSRAM"
			(at 0 0 270)
			(unlocked yes)
			(layer "F.Fab")
			(hide yes)
			(effects
				(font
					(size 1 1)
					(thickness 0.15)
				)
			)
		)
		(property "Color" "Green"
			(at 0 0 270)
			(unlocked yes)
			(layer "F.Fab")
			(hide yes)
			(effects
				(font
					(size 1 1)
					(thickness 0.15)
				)
			)
		)
		(property "Author" "Antmicro"
			(at 0 0 270)
			(unlocked yes)
			(layer "F.Fab")
			(hide yes)
			(effects
				(font
					(size 1 1)
					(thickness 0.15)
				)
			)
		)
		(property "License" "Apache-2.0"
			(at 0 0 270)
			(unlocked yes)
			(layer "F.Fab")
			(hide yes)
			(effects
				(font
					(size 1 1)
					(thickness 0.15)
				)
			)
		)
		(sheetname "/Power/")
		(sheetfile "power.kicad_sch")
		(attr smd)
		(fp_line
			(start 0.22 0.35)
			(end -0.22 0.35)
			(stroke
				(width 0.15)
				(type solid)
			)
			(layer "F.SilkS")
		)
		(fp_line
			(start -0.094672 0.201008)
			(end -0.094672 -0.198992)
			(stroke
				(width 0.1)
				(type solid)
			)
			(layer "F.SilkS")
		)
		(fp_line
			(start 0.105328 0.201008)
			(end -0.094672 0.001008)
			(stroke
				(width 0.1)
				(type solid)
			)
			(layer "F.SilkS")
		)
		(fp_line
			(start 0.105328 0.201008)
			(end 0.105328 -0.198992)
			(stroke
				(width 0.1)
				(type solid)
			)
			(layer "F.SilkS")
		)
		(fp_line
			(start -0.094672 0.001008)
			(end -0.24 0.001008)
			(stroke
				(width 0.1)
				(type solid)
			)
			(layer "F.SilkS")
		)
		(fp_line
			(start -0.094672 0.001008)
			(end 0.105328 -0.198992)
			(stroke
				(width 0.1)
				(type solid)
			)
			(layer "F.SilkS")
		)
		(fp_line
			(start 0.105328 0.001008)
			(end 0.24 0.001)
			(stroke
				(width 0.1)
				(type solid)
			)
			(layer "F.SilkS")
		)
		(fp_line
			(start -1.18 -0.319)
			(end -1.18 0.321)
			(stroke
				(width 0.15)
				(type solid)
			)
			(layer "F.SilkS")
		)
		(fp_line
			(start 0.22 -0.35)
			(end -0.22 -0.35)
			(stroke
				(width 0.15)
				(type solid)
			)
			(layer "F.SilkS")
		)
		(fp_rect
			(start 1.25 0.65)
			(end -1.25 -0.65)
			(stroke
				(width 0.05)
				(type solid)
			)
			(fill no)
			(layer "F.CrtYd")
		)
		(fp_line
			(start -0.199 0.2)
			(end -0.199 0.1)
			(stroke
				(width 0.15)
				(type solid)
			)
			(layer "F.Fab")
		)
		(fp_line
			(start 0.201 0.2)
			(end 0.201 0)
			(stroke
				(width 0.15)
				(type solid)
			)
			(layer "F.Fab")
		)
		(fp_line
			(start -0.199 0)
			(end -0.597 0)
			(stroke
				(width 0.15)
				(type solid)
			)
			(layer "F.Fab")
		)
		(fp_line
			(start -0.101 0)
			(end 0.201 0.2)
			(stroke
				(width 0.15)
				(type solid)
			)
			(layer "F.Fab")
		)
		(fp_line
			(start 0.201 0)
			(end 0.201 -0.202)
			(stroke
				(width 0.15)
				(type solid)
			)
			(layer "F.Fab")
		)
		(fp_line
			(start 0.599 0)
			(end 0.201 0)
			(stroke
				(width 0.15)
				(type solid)
			)
			(layer "F.Fab")
		)
		(fp_line
			(start -0.199 -0.202)
			(end -0.199 0.1)
			(stroke
				(width 0.15)
				(type solid)
			)
			(layer "F.Fab")
		)
		(fp_line
			(start 0.201 -0.202)
			(end -0.101 0)
			(stroke
				(width 0.15)
				(type solid)
			)
			(layer "F.Fab")
		)
		(fp_rect
			(start 0.848 0.4)
			(end -0.85 -0.402)
			(stroke
				(width 0.15)
				(type solid)
			)
			(fill no)
			(layer "F.Fab")
		)
		(fp_text user "License: Apache-2.0"
			(at -1.4224 3.599 270)
			(layer "F.Fab")
			(effects
				(font
					(size 0.7 0.7)
					(thickness 0.15)
				)
				(justify left bottom)
			)
		)
		(fp_text user "${REFERENCE}"
			(at -1.4224 5.999 270)
			(layer "F.Fab")
			(effects
				(font
					(size 0.7 0.7)
					(thickness 0.15)
				)
				(justify left bottom)
			)
		)
		(fp_text user "Author: Antmicro"
			(at -1.4224 4.799 270)
			(layer "F.Fab")
			(effects
				(font
					(size 0.7 0.7)
					(thickness 0.15)
				)
				(justify left bottom)
			)
		)
		(pad "1" smd roundrect
			(at -0.7 0 90)
			(size 0.8 1)
			(layers "F.Cu" "F.Mask" "F.Paste")
			(roundrect_rratio 0.2)
			(net 89 "Net-(D11-C)")
			(pinfunction "C")
			(pintype "passive")
		)
		(pad "2" smd roundrect
			(at 0.7 0 90)
			(size 0.8 1)
			(layers "F.Cu" "F.Mask" "F.Paste")
			(roundrect_rratio 0.2)
			(net 79 "Net-(D11-A)")
			(pinfunction "A")
			(pintype "passive")
		)
	)
	(footprint "antmicro-footprints:R_0402_1005Metric"
		(layer "F.Cu")
		(at 57.15 127.45 180)
		(descr "Resistor SMD 0402")
		(tags "resistor SMD 0402")
		(property "Reference" "R144"
			(at -1.5 -0.772697 0)
			(layer "F.SilkS")
			(effects
				(font
					(size 0.7 0.7)
					(thickness 0.15)
				)
				(justify right top)
			)
		)
		(property "Value" "R_1k_0402"
			(at -1.011843 1.772046 0)
			(layer "F.Fab")
			(hide yes)
			(effects
				(font
					(size 0.7 0.7)
					(thickness 0.15)
				)
				(justify right top)
			)
		)
		(property "Datasheet" "https://www.bourns.com/docs/product-datasheets/cr.pdf"
			(at 0 0 0)
			(layer "F.Fab")
			(hide yes)
			(effects
				(font
					(size 1.27 1.27)
					(thickness 0.15)
				)
			)
		)
		(property "Description" "SMD Chip Resistor, 1 kohm, ± 1%, 63 mW, 0402 [1005 Metric], Thick Film, General Purpose"
			(at 0 0 0)
			(layer "F.Fab")
			(hide yes)
			(effects
				(font
					(size 1.27 1.27)
					(thickness 0.15)
				)
			)
		)
		(property "MPN" "CR0402-FX-1001GLF"
			(at 0 0 180)
			(unlocked yes)
			(layer "F.Fab")
			(hide yes)
			(effects
				(font
					(size 1 1)
					(thickness 0.15)
				)
			)
		)
		(property "Manufacturer" "Bourns"
			(at 0 0 180)
			(unlocked yes)
			(layer "F.Fab")
			(hide yes)
			(effects
				(font
					(size 1 1)
					(thickness 0.15)
				)
			)
		)
		(property "License" "Apache-2.0"
			(at 0 0 180)
			(unlocked yes)
			(layer "F.Fab")
			(hide yes)
			(effects
				(font
					(size 1 1)
					(thickness 0.15)
				)
			)
		)
		(property "Author" "Antmicro"
			(at 0 0 180)
			(unlocked yes)
			(layer "F.Fab")
			(hide yes)
			(effects
				(font
					(size 1 1)
					(thickness 0.15)
				)
			)
		)
		(property "Val" "1k"
			(at 0 0 180)
			(unlocked yes)
			(layer "F.Fab")
			(hide yes)
			(effects
				(font
					(size 1 1)
					(thickness 0.15)
				)
			)
		)
		(property "Tolerance" "1%"
			(at 0 0 180)
			(unlocked yes)
			(layer "F.Fab")
			(hide yes)
			(effects
				(font
					(size 1 1)
					(thickness 0.15)
				)
			)
		)
		(sheetname "/Power/")
		(sheetfile "power.kicad_sch")
		(attr smd)
		(fp_poly
			(pts
				(xy -0.925 -0.47) (xy 0.925 -0.47) (xy 0.925 0.47) (xy -0.925 0.47)
			)
			(stroke
				(width 0.05)
				(type default)
			)
			(fill no)
			(layer "F.CrtYd")
		)
		(fp_poly
			(pts
				(xy -0.5 -0.25) (xy 0.5 -0.25) (xy 0.5 0.25) (xy -0.5 0.25)
			)
			(stroke
				(width 0.15)
				(type solid)
			)
			(fill no)
			(layer "F.Fab")
		)
		(pad "1" smd roundrect
			(at -0.48 0 180)
			(size 0.59 0.64)
			(layers "F.Cu" "F.Mask" "F.Paste")
			(roundrect_rratio 0.25)
			(net 28 "GND")
			(pintype "passive")
		)
		(pad "2" smd roundrect
			(at 0.48 0 180)
			(size 0.59 0.64)
			(layers "F.Cu" "F.Mask" "F.Paste")
			(roundrect_rratio 0.25)
			(net 415 "Net-(D16-C)")
			(pintype "passive")
		)
	)
	(footprint "antmicro-footprints:C_0603_1608Metric_EIA"
		(layer "F.Cu")
		(at 66.7 83.5 180)
		(descr "Capacitor SMD 0603, IPC-7351 Density Level A")
		(tags "Capacitor 0603")
		(property "Reference" "C123"
			(at -1.95 4.56 0)
			(layer "F.SilkS")
			(effects
				(font
					(size 0.7 0.7)
					(thickness 0.15)
				)
				(justify right top)
			)
		)
		(property "Value" "C_22u_16V_0603"
			(at -1.42757 1.770288 0)
			(layer "F.Fab")
			(hide yes)
			(effects
				(font
					(size 0.7 0.7)
					(thickness 0.15)
				)
				(justify right top)
			)
		)
		(property "Datasheet" "https://product.samsungsem.com/mlcc/CL10A226MO7JZN.do"
			(at 0 0 0)
			(layer "F.Fab")
			(hide yes)
			(effects
				(font
					(size 1.27 1.27)
					(thickness 0.15)
				)
			)
		)
		(property "Description" "SMD Multilayer Ceramic Capacitor"
			(at 0 0 0)
			(layer "F.Fab")
			(hide yes)
			(effects
				(font
					(size 1.27 1.27)
					(thickness 0.15)
				)
			)
		)
		(property "MPN" "CL10A226MO7JZNC"
			(at 0 0 180)
			(unlocked yes)
			(layer "F.Fab")
			(hide yes)
			(effects
				(font
					(size 1 1)
					(thickness 0.15)
				)
			)
		)
		(property "Manufacturer" "Samsung Electro-Mechanics"
			(at 0 0 180)
			(unlocked yes)
			(layer "F.Fab")
			(hide yes)
			(effects
				(font
					(size 1 1)
					(thickness 0.15)
				)
			)
		)
		(property "License" "Apache-2.0"
			(at 0 0 180)
			(unlocked yes)
			(layer "F.Fab")
			(hide yes)
			(effects
				(font
					(size 1 1)
					(thickness 0.15)
				)
			)
		)
		(property "Author" "Antmicro"
			(at 0 0 180)
			(unlocked yes)
			(layer "F.Fab")
			(hide yes)
			(effects
				(font
					(size 1 1)
					(thickness 0.15)
				)
			)
		)
		(property "Val" "22u"
			(at 0 0 180)
			(unlocked yes)
			(layer "F.Fab")
			(hide yes)
			(effects
				(font
					(size 1 1)
					(thickness 0.15)
				)
			)
		)
		(property "Voltage" "16V"
			(at 0 0 180)
			(unlocked yes)
			(layer "F.Fab")
			(hide yes)
			(effects
				(font
					(size 1 1)
					(thickness 0.15)
				)
			)
		)
		(property "Dielectric" ""
			(at 0 0 180)
			(unlocked yes)
			(layer "F.Fab")
			(hide yes)
			(effects
				(font
					(size 1 1)
					(thickness 0.15)
				)
			)
		)
		(sheetname "/X710-AT2 power/")
		(sheetfile "x710-at2-power.kicad_sch")
		(attr smd)
		(fp_line
			(start -0.15 0.55)
			(end 0.15 0.55)
			(stroke
				(width 0.15)
				(type solid)
			)
			(layer "F.SilkS")
		)
		(fp_line
			(start -0.15 -0.55)
			(end 0.15 -0.55)
			(stroke
				(width 0.15)
				(type solid)
			)
			(layer "F.SilkS")
		)
		(fp_rect
			(start -1.25 -0.65)
			(end 1.25 0.65)
			(stroke
				(width 0.05)
				(type solid)
			)
			(fill no)
			(layer "F.CrtYd")
		)
		(fp_rect
			(start -0.8 -0.45)
			(end 0.8 0.45)
			(stroke
				(width 0.15)
				(type solid)
			)
			(fill no)
			(layer "F.Fab")
		)
		(pad "1" smd roundrect
			(at -0.7 0 180)
			(size 0.8 1.1)
			(layers "F.Cu" "F.Mask" "F.Paste")
			(roundrect_rratio 0.2)
			(net 28 "GND")
			(pintype "passive")
		)
		(pad "2" smd roundrect
			(at 0.7 0 180)
			(size 0.8 1.1)
			(layers "F.Cu" "F.Mask" "F.Paste")
			(roundrect_rratio 0.2)
			(net 9 "VCCD")
			(pintype "passive")
		)
	)
	(footprint "antmicro-footprints:TP_SMD_0.75mm"
		(layer "F.Cu")
		(at 52.05 128.55 -90)
		(property "Reference" "TP21"
			(at -3.05 0.31 90)
			(layer "F.SilkS")
			(hide yes)
			(effects
				(font
					(size 0.7 0.7)
					(thickness 0.15)
				)
				(justify right top)
			)
		)
		(property "Value" "TP_0.75mm_SMD"
			(at 0 1.2 90)
			(layer "F.Fab")
			(hide yes)
			(effects
				(font
					(size 0.7 0.7)
					(thickness 0.15)
				)
				(justify right top)
			)
		)
		(property "Description" "SMT test point"
			(at 0 0 90)
			(layer "F.Fab")
			(hide yes)
			(effects
				(font
					(size 1.27 1.27)
					(thickness 0.15)
				)
			)
		)
		(property "MPN" ""
			(at 0 0 270)
			(unlocked yes)
			(layer "F.Fab")
			(hide yes)
			(effects
				(font
					(size 1 1)
					(thickness 0.15)
				)
			)
		)
		(property "Manufacturer" ""
			(at 0 0 270)
			(unlocked yes)
			(layer "F.Fab")
			(hide yes)
			(effects
				(font
					(size 1 1)
					(thickness 0.15)
				)
			)
		)
		(property "Author" "Antmicro"
			(at 0 0 270)
			(unlocked yes)
			(layer "F.Fab")
			(hide yes)
			(effects
				(font
					(size 1 1)
					(thickness 0.15)
				)
			)
		)
		(property "License" "Apache-2.0"
			(at 0 0 270)
			(unlocked yes)
			(layer "F.Fab")
			(hide yes)
			(effects
				(font
					(size 1 1)
					(thickness 0.15)
				)
			)
		)
		(sheetname "/Power/")
		(sheetfile "power.kicad_sch")
		(attr exclude_from_pos_files exclude_from_bom)
		(fp_circle
			(center 0 0)
			(end 0.475 0)
			(stroke
				(width 0.05)
				(type default)
			)
			(fill no)
			(layer "F.CrtYd")
		)
		(pad "1" smd circle
			(at 0 0 270)
			(size 0.75 0.75)
			(layers "F.Cu" "F.Mask")
			(net 255 "/Power/+3V3_OUT")
			(pinfunction "1")
			(pintype "passive")
		)
	)
	(footprint "antmicro-footprints:C_0603_1608Metric"
		(layer "F.Cu")
		(at 97.9 102 180)
		(descr "Capacitor SMD 0603")
		(tags "capacitor 0603")
		(property "Reference" "C149"
			(at -3.75 0.35 0)
			(layer "F.SilkS")
			(effects
				(font
					(size 0.7 0.7)
					(thickness 0.15)
				)
				(justify left top)
			)
		)
		(property "Value" "C_10u_10V_X7R_0603"
			(at -1.42757 1.770288 0)
			(layer "F.Fab")
			(hide yes)
			(effects
				(font
					(size 0.7 0.7)
					(thickness 0.15)
				)
				(justify right top)
			)
		)
		(property "Datasheet" "https://www.murata.com/products/productdetail?partno=GRM188Z71A106KA73%23"
			(at 0 0 0)
			(layer "F.Fab")
			(hide yes)
			(effects
				(font
					(size 1.27 1.27)
					(thickness 0.15)
				)
			)
		)
		(property "Description" "SMD Multilayer Ceramic Capacitor,  10µF, 10V, 0603, ±10%, X7R"
			(at 0 0 0)
			(layer "F.Fab")
			(hide yes)
			(effects
				(font
					(size 1.27 1.27)
					(thickness 0.15)
				)
			)
		)
		(property "MPN" "GRM188Z71A106KA73D"
			(at 0 0 180)
			(unlocked yes)
			(layer "F.Fab")
			(hide yes)
			(effects
				(font
					(size 1 1)
					(thickness 0.15)
				)
			)
		)
		(property "Val" "10u"
			(at 0 0 180)
			(unlocked yes)
			(layer "F.Fab")
			(hide yes)
			(effects
				(font
					(size 1 1)
					(thickness 0.15)
				)
			)
		)
		(property "Voltage" "10V"
			(at 0 0 180)
			(unlocked yes)
			(layer "F.Fab")
			(hide yes)
			(effects
				(font
					(size 1 1)
					(thickness 0.15)
				)
			)
		)
		(property "Dielectric" "X7R"
			(at 0 0 180)
			(unlocked yes)
			(layer "F.Fab")
			(hide yes)
			(effects
				(font
					(size 1 1)
					(thickness 0.15)
				)
			)
		)
		(property "Manufacturer" "Murata"
			(at 0 0 180)
			(unlocked yes)
			(layer "F.Fab")
			(hide yes)
			(effects
				(font
					(size 1 1)
					(thickness 0.15)
				)
			)
		)
		(property "License" "Apache-2.0"
			(at 0 0 180)
			(unlocked yes)
			(layer "F.Fab")
			(hide yes)
			(effects
				(font
					(size 1 1)
					(thickness 0.15)
				)
			)
		)
		(property "Author" "Antmicro"
			(at 0 0 180)
			(unlocked yes)
			(layer "F.Fab")
			(hide yes)
			(effects
				(font
					(size 1 1)
					(thickness 0.15)
				)
			)
		)
		(sheetname "/X710-AT2 power/")
		(sheetfile "x710-at2-power.kicad_sch")
		(attr smd)
		(fp_line
			(start -0.15 0.4)
			(end 0.15 0.4)
			(stroke
				(width 0.15)
				(type solid)
			)
			(layer "F.SilkS")
		)
		(fp_line
			(start -0.15 -0.4)
			(end 0.15 -0.4)
			(stroke
				(width 0.15)
				(type solid)
			)
			(layer "F.SilkS")
		)
		(fp_rect
			(start -1.25 -0.65)
			(end 1.25 0.65)
			(stroke
				(width 0.05)
				(type solid)
			)
			(fill no)
			(layer "F.CrtYd")
		)
		(fp_rect
			(start -0.8 -0.4)
			(end 0.8 0.4)
			(stroke
				(width 0.15)
				(type solid)
			)
			(fill no)
			(layer "F.Fab")
		)
		(pad "1" smd roundrect
			(at -0.7 0 180)
			(size 0.8 1)
			(layers "F.Cu" "F.Mask" "F.Paste")
			(roundrect_rratio 0.2)
			(net 28 "GND")
			(pintype "passive")
		)
		(pad "2" smd roundrect
			(at 0.7 0 180)
			(size 0.8 1)
			(layers "F.Cu" "F.Mask" "F.Paste")
			(roundrect_rratio 0.2)
			(net 7 "+3V3")
			(pintype "passive")
		)
	)
	(footprint "antmicro-footprints:R_0402_1005Metric"
		(layer "F.Cu")
		(at 58.099999 100.550002 90)
		(descr "Resistor SMD 0402")
		(tags "resistor SMD 0402")
		(property "Reference" "R17"
			(at -1.359998 1.210001 90)
			(layer "F.SilkS")
			(effects
				(font
					(size 0.7 0.7)
					(thickness 0.15)
				)
				(justify left bottom)
			)
		)
		(property "Value" "R_100k_0402"
			(at -1.011843 1.772046 90)
			(layer "F.Fab")
			(hide yes)
			(effects
				(font
					(size 0.7 0.7)
					(thickness 0.15)
				)
				(justify left bottom)
			)
		)
		(property "Datasheet" "https://www.bourns.com/docs/product-datasheets/cr.pdf"
			(at 0 0 90)
			(layer "F.Fab")
			(hide yes)
			(effects
				(font
					(size 1.27 1.27)
					(thickness 0.15)
				)
			)
		)
		(property "Description" "SMD Chip Resistor, 100 kohm, ± 1%, 62.5 mW, 0402 [1005 Metric], Thick Film, General Purpose"
			(at 0 0 90)
			(layer "F.Fab")
			(hide yes)
			(effects
				(font
					(size 1.27 1.27)
					(thickness 0.15)
				)
			)
		)
		(property "MPN" "CR0402-FX-1003GLF"
			(at 0 0 90)
			(unlocked yes)
			(layer "F.Fab")
			(hide yes)
			(effects
				(font
					(size 1 1)
					(thickness 0.15)
				)
			)
		)
		(property "Manufacturer" "Bourns"
			(at 0 0 90)
			(unlocked yes)
			(layer "F.Fab")
			(hide yes)
			(effects
				(font
					(size 1 1)
					(thickness 0.15)
				)
			)
		)
		(property "License" "Apache-2.0"
			(at 0 0 90)
			(unlocked yes)
			(layer "F.Fab")
			(hide yes)
			(effects
				(font
					(size 1 1)
					(thickness 0.15)
				)
			)
		)
		(property "Author" "Antmicro"
			(at 0 0 90)
			(unlocked yes)
			(layer "F.Fab")
			(hide yes)
			(effects
				(font
					(size 1 1)
					(thickness 0.15)
				)
			)
		)
		(property "Val" "100k"
			(at 0 0 90)
			(unlocked yes)
			(layer "F.Fab")
			(hide yes)
			(effects
				(font
					(size 1 1)
					(thickness 0.15)
				)
			)
		)
		(property "Tolerance" "1%"
			(at 0 0 90)
			(unlocked yes)
			(layer "F.Fab")
			(hide yes)
			(effects
				(font
					(size 1 1)
					(thickness 0.15)
				)
			)
		)
		(sheetname "/Power/")
		(sheetfile "power.kicad_sch")
		(attr smd)
		(fp_rect
			(start -0.925 -0.47)
			(end 0.925 0.47)
			(stroke
				(width 0.05)
				(type default)
			)
			(fill no)
			(layer "F.CrtYd")
		)
		(fp_rect
			(start -0.5 -0.25)
			(end 0.5 0.25)
			(stroke
				(width 0.15)
				(type solid)
			)
			(fill no)
			(layer "F.Fab")
		)
		(pad "1" smd roundrect
			(at -0.48 0 90)
			(size 0.59 0.64)
			(layers "F.Cu" "F.Mask" "F.Paste")
			(roundrect_rratio 0.25)
			(net 369 "/Power/1V88_PG")
			(pintype "passive")
		)
		(pad "2" smd roundrect
			(at 0.48 0 90)
			(size 0.59 0.64)
			(layers "F.Cu" "F.Mask" "F.Paste")
			(roundrect_rratio 0.25)
			(net 324 "/Power/1V88_VCC")
			(pintype "passive")
		)
	)
)
